# SCM (Grand Teton) — schematic netlist excerpt (pin names and nets, part order shuffled) for the footprints in the layout excerpt that follows; sources: Cadence DE-HDL packaged netlist, KiCad conversion of 12092022_DA0F0TMDCD0_F0T_Management_Board_D_brd_V3_OCP.brd

R58  Q_RES  4.7K 1% EMPTY  pkg 0402LF  page 21 : A = P3V3_AUX ; B = SPI_BMC_HOLD0_N
D14  Q_LED  IC  pkg THLF  page 49 : A = PWR_LED_P5V_AUX ; C = PWR_LED_BUF_N_R

(kicad_pcb
	(version 20260206)
	(generator "pcbnew")
	(generator_version "10.0")
	(general
		(thickness 1.6)
		(legacy_teardrops no)
	)
	(paper "A4")
	(title_block
		(title "12092022_DA0F0TMDCD0_F0T_Management_Board_D_brd_V3_OCP.brd")
		(comment 1 "Grand Teton / footprints 192-193 of 1440")
	)
	(layers
		(0 "F.Cu" signal "TOP")
		(4 "In1.Cu" signal "GND")
		(6 "In2.Cu" signal "IN1")
		(8 "In3.Cu" signal "GND1")
		(10 "In4.Cu" signal "IN2")
		(12 "In5.Cu" signal "VCC")
		(14 "In6.Cu" signal "VCC1")
		(16 "In7.Cu" signal "IN3")
		(18 "In8.Cu" signal "GND2")
		(20 "In9.Cu" signal "IN4")
		(22 "In10.Cu" signal "GND3")
		(2 "B.Cu" signal "BOTTOM")
		(9 "F.Adhes" user "F.Adhesive")
		(11 "B.Adhes" user "B.Adhesive")
		(13 "F.Paste" user "Package Geometry/Pastemask Top")
		(15 "B.Paste" user "Package Geometry/Pastemask Bottom")
		(5 "F.SilkS" user "Ref Des/Silkscreen Top")
		(7 "B.SilkS" user "Ref Des/Silkscreen Bottom")
		(1 "F.Mask" user "Board Geometry/Soldermask Top")
		(3 "B.Mask" user "Board Geometry/Soldermask Bottom")
		(17 "Dwgs.User" user "User.Drawings")
		(19 "Cmts.User" user "User.Comments")
		(21 "Eco1.User" user "User.Eco1")
		(23 "Eco2.User" user "User.Eco2")
		(25 "Edge.Cuts" user "Board Geometry/Outline")
		(27 "Margin" user)
		(31 "F.CrtYd" user "Package Geometry/Place Bound Top")
		(29 "B.CrtYd" user "Package Geometry/Place Bound Bottom")
		(35 "F.Fab" user "Ref Des/Assembly Top")
		(33 "B.Fab" user "Ref Des/Assembly Bottom")
	)
	(footprint ""
		(layer "F.Cu")
		(at 16.230092 -6.290056)
		(property "Reference" "D14"
			(at 1.448308 -2.547874 0)
			(unlocked yes)
			(layer "F.SilkS")
			(effects
				(font
					(size 0.7874 0.5842)
					(thickness 0.1524)
				)
				(justify left)
			)
		)
		(property "Value" ""
			(at 0 0 0)
			(layer "F.Fab")
			(effects
				(font
					(size 1.27 1.27)
				)
			)
		)
		(duplicate_pad_numbers_are_jumpers no)
		(fp_line
			(start -1.080008 -1.999996)
			(end 3.620008 -1.999996)
			(stroke
				(width 0.1524)
				(type default)
			)
			(layer "F.SilkS")
		)
		(fp_line
			(start -1.080008 3.999992)
			(end -1.080008 -1.999996)
			(stroke
				(width 0.1524)
				(type default)
			)
			(layer "F.SilkS")
		)
		(fp_line
			(start -0.230124 3.999992)
			(end -1.080008 3.999992)
			(stroke
				(width 0.1524)
				(type default)
			)
			(layer "F.SilkS")
		)
		(fp_line
			(start -0.230124 5.199888)
			(end -0.230124 3.999992)
			(stroke
				(width 0.1524)
				(type default)
			)
			(layer "F.SilkS")
		)
		(fp_line
			(start 2.770124 3.999992)
			(end 2.770124 5.199888)
			(stroke
				(width 0.1524)
				(type default)
			)
			(layer "F.SilkS")
		)
		(fp_line
			(start 3.620008 -1.999996)
			(end 3.620008 3.999992)
			(stroke
				(width 0.1524)
				(type default)
			)
			(layer "F.SilkS")
		)
		(fp_line
			(start 3.620008 3.999992)
			(end 2.770124 3.999992)
			(stroke
				(width 0.1524)
				(type default)
			)
			(layer "F.SilkS")
		)
		(fp_arc
			(start 1.27 6.700012)
			(mid 0.209252 6.260636)
			(end -0.230124 5.199888)
			(stroke
				(width 0.1524)
				(type default)
			)
			(layer "F.SilkS")
		)
		(fp_arc
			(start 2.770124 5.199888)
			(mid 2.330748 6.260636)
			(end 1.27 6.700012)
			(stroke
				(width 0.1524)
				(type default)
			)
			(layer "F.SilkS")
		)
		(fp_line
			(start -1.080008 -1.999996)
			(end 3.620008 -1.999996)
			(stroke
				(width 0.1)
				(type default)
			)
			(layer "F.Fab")
		)
		(fp_line
			(start -1.080008 3.999992)
			(end -1.080008 -1.999996)
			(stroke
				(width 0.1)
				(type default)
			)
			(layer "F.Fab")
		)
		(fp_line
			(start -0.230124 3.999992)
			(end -1.080008 3.999992)
			(stroke
				(width 0.1)
				(type default)
			)
			(layer "F.Fab")
		)
		(fp_line
			(start -0.230124 5.199888)
			(end -0.230124 3.999992)
			(stroke
				(width 0.1)
				(type default)
			)
			(layer "F.Fab")
		)
		(fp_line
			(start 2.770124 3.999992)
			(end 2.770124 5.199888)
			(stroke
				(width 0.1)
				(type default)
			)
			(layer "F.Fab")
		)
		(fp_line
			(start 3.620008 -1.999996)
			(end 3.620008 3.999992)
			(stroke
				(width 0.1)
				(type default)
			)
			(layer "F.Fab")
		)
		(fp_line
			(start 3.620008 3.999992)
			(end 2.770124 3.999992)
			(stroke
				(width 0.1)
				(type default)
			)
			(layer "F.Fab")
		)
		(fp_arc
			(start 1.27 6.700012)
			(mid 0.209252 6.260636)
			(end -0.230124 5.199888)
			(stroke
				(width 0.1)
				(type default)
			)
			(layer "F.Fab")
		)
		(fp_arc
			(start 2.770124 5.199888)
			(mid 2.330748 6.260636)
			(end 1.27 6.700012)
			(stroke
				(width 0.1)
				(type default)
			)
			(layer "F.Fab")
		)
		(pad "A" thru_hole rect
			(at 0 0)
			(size 1.2192 1.2192)
			(drill 0.8128)
			(layers "*.Cu" "*.Mask")
			(remove_unused_layers no)
			(net "PWR_LED_P5V_AUX")
			(clearance 0.0508)
			(thermal_gap 0.0508)
			(padstack
				(mode front_inner_back)
				(layer "Inner"
					(shape circle)
					(size 1.2192 1.2192)
					(clearance 0.0508)
				)
				(layer "B.Cu"
					(shape rect)
					(size 1.2192 1.2192)
					(clearance 0.0508)
				)
			)
		)
		(pad "C" thru_hole circle
			(at 2.54 0)
			(size 1.2192 1.2192)
			(drill 0.8128)
			(layers "*.Cu" "*.Mask")
			(remove_unused_layers no)
			(net "PWR_LED_BUF_N_R")
			(clearance 0.0508)
			(thermal_gap 0.0508)
		)
	)
	(footprint ""
		(layer "F.Cu")
		(at 26.289 -68.834 90)
		(property "Reference" "R58"
			(at 0 0 90)
			(layer "F.SilkS")
			(hide yes)
			(effects
				(font
					(size 1.27 1.27)
				)
			)
		)
		(property "Value" ""
			(at 0 0 90)
			(layer "F.Fab")
			(effects
				(font
					(size 1.27 1.27)
				)
			)
		)
		(duplicate_pad_numbers_are_jumpers no)
		(fp_line
			(start 0.7874 -0.4064)
			(end 0.7874 0.4064)
			(stroke
				(width 0.1524)
				(type default)
			)
			(layer "F.SilkS")
		)
		(fp_line
			(start -0.7874 -0.4064)
			(end 0.7874 -0.4064)
			(stroke
				(width 0.1524)
				(type default)
			)
			(layer "F.SilkS")
		)
		(fp_line
			(start 0.7874 0.4064)
			(end -0.7874 0.4064)
			(stroke
				(width 0.1524)
				(type default)
			)
			(layer "F.SilkS")
		)
		(fp_line
			(start -0.7874 0.4064)
			(end -0.7874 -0.4064)
			(stroke
				(width 0.1524)
				(type default)
			)
			(layer "F.SilkS")
		)
		(fp_line
			(start -0.12065 -0.305054)
			(end -0.12065 -0.2794)
			(stroke
				(width 0.1)
				(type default)
			)
			(layer "F.Fab")
		)
		(fp_line
			(start -0.67945 -0.305054)
			(end -0.12065 -0.305054)
			(stroke
				(width 0.1)
				(type default)
			)
			(layer "F.Fab")
		)
		(fp_line
			(start 0.67945 -0.3048)
			(end 0.67945 0.3048)
			(stroke
				(width 0.1)
				(type default)
			)
			(layer "F.Fab")
		)
		(fp_line
			(start 0.12065 -0.3048)
			(end 0.67945 -0.3048)
			(stroke
				(width 0.1)
				(type default)
			)
			(layer "F.Fab")
		)
		(fp_line
			(start 0.12065 -0.2794)
			(end 0.12065 -0.3048)
			(stroke
				(width 0.1)
				(type default)
			)
			(layer "F.Fab")
		)
		(fp_line
			(start -0.12065 -0.2794)
			(end 0.12065 -0.2794)
			(stroke
				(width 0.1)
				(type default)
			)
			(layer "F.Fab")
		)
		(fp_line
			(start 0.120396 0.2794)
			(end -0.12065 0.2794)
			(stroke
				(width 0.1)
				(type default)
			)
			(layer "F.Fab")
		)
		(fp_line
			(start -0.12065 0.2794)
			(end -0.12065 0.3048)
			(stroke
				(width 0.1)
				(type default)
			)
			(layer "F.Fab")
		)
		(fp_line
			(start 0.67945 0.3048)
			(end 0.120396 0.3048)
			(stroke
				(width 0.1)
				(type default)
			)
			(layer "F.Fab")
		)
		(fp_line
			(start 0.120396 0.3048)
			(end 0.120396 0.2794)
			(stroke
				(width 0.1)
				(type default)
			)
			(layer "F.Fab")
		)
		(fp_line
			(start -0.12065 0.3048)
			(end -0.67945 0.3048)
			(stroke
				(width 0.1)
				(type default)
			)
			(layer "F.Fab")
		)
		(fp_line
			(start -0.67945 0.3048)
			(end -0.67945 -0.305054)
			(stroke
				(width 0.1)
				(type default)
			)
			(layer "F.Fab")
		)
		(pad "1" smd circle
			(at -0.40005 0 90)
			(size 0 0)
			(layers "F.Cu" "F.Mask" "F.Paste")
			(net "P3V3_AUX")
		)
		(pad "2" smd circle
			(at 0.40005 0 90)
			(size 0 0)
			(layers "F.Cu" "F.Mask" "F.Paste")
			(net "SPI_BMC_HOLD0_N")
		)
	)
)
